(kicad_pcb
	(version 20260206)
	(generator "pcbnew")
	(generator_version "10.0")
	(general
		(thickness 1.6)
		(legacy_teardrops no)
	)
	(paper "A4")
	(title_block
		(title "03242023_DA0F0TMBIJ0_F0T_Motherboard_J_brd_V01_OCP.brd")
		(comment 1 "Grand Teton / footprints 2411-2413 of 6105")
	)
	(layers
		(0 "F.Cu" signal "TOP")
		(4 "In1.Cu" signal "GND")
		(6 "In2.Cu" signal "IN1")
		(8 "In3.Cu" signal "GND1")
		(10 "In4.Cu" signal "IN2")
		(12 "In5.Cu" signal "GND2")
		(14 "In6.Cu" signal "IN3")
		(16 "In7.Cu" signal "GND3")
		(18 "In8.Cu" signal "VCC")
		(20 "In9.Cu" signal "VCC1")
		(22 "In10.Cu" signal "GND4")
		(24 "In11.Cu" signal "IN4")
		(26 "In12.Cu" signal "GND5")
		(28 "In13.Cu" signal "IN5")
		(30 "In14.Cu" signal "GND6")
		(32 "In15.Cu" signal "IN6")
		(34 "In16.Cu" signal "GND7")
		(2 "B.Cu" signal "BOTTOM")
		(9 "F.Adhes" user "F.Adhesive")
		(11 "B.Adhes" user "B.Adhesive")
		(13 "F.Paste" user "Package Geometry/Pastemask Top")
		(15 "B.Paste" user "Package Geometry/Pastemask Bottom")
		(5 "F.SilkS" user "Ref Des/Silkscreen Top")
		(7 "B.SilkS" user "Ref Des/Silkscreen Bottom")
		(1 "F.Mask" user "Board Geometry/Soldermask Top")
		(3 "B.Mask" user "Board Geometry/Soldermask Bottom")
		(17 "Dwgs.User" user "User.Drawings")
		(19 "Cmts.User" user "User.Comments")
		(21 "Eco1.User" user "User.Eco1")
		(23 "Eco2.User" user "User.Eco2")
		(25 "Edge.Cuts" user "Board Geometry/Outline")
		(27 "Margin" user)
		(31 "F.CrtYd" user "Package Geometry/Place Bound Top")
		(29 "B.CrtYd" user "Package Geometry/Place Bound Bottom")
		(35 "F.Fab" user "Ref Des/Assembly Top")
		(33 "B.Fab" user "Ref Des/Assembly Bottom")
	)
	(footprint ""
		(layer "F.Cu")
		(at 176.6824 -93.538548 90)
		(property "Reference" "R4586"
			(at 0 0 90)
			(layer "F.SilkS")
			(hide yes)
			(effects
				(font
					(size 1.27 1.27)
				)
			)
		)
		(property "Value" ""
			(at 0 0 90)
			(layer "F.Fab")
			(effects
				(font
					(size 1.27 1.27)
				)
			)
		)
		(duplicate_pad_numbers_are_jumpers no)
		(fp_line
			(start 0.7874 -0.4064)
			(end 0.7874 0.4064)
			(stroke
				(width 0.1524)
				(type default)
			)
			(layer "F.SilkS")
		)
		(fp_line
			(start -0.7874 -0.4064)
			(end 0.7874 -0.4064)
			(stroke
				(width 0.1524)
				(type default)
			)
			(layer "F.SilkS")
		)
		(fp_line
			(start 0.7874 0.4064)
			(end -0.7874 0.4064)
			(stroke
				(width 0.1524)
				(type default)
			)
			(layer "F.SilkS")
		)
		(fp_line
			(start -0.7874 0.4064)
			(end -0.7874 -0.4064)
			(stroke
				(width 0.1524)
				(type default)
			)
			(layer "F.SilkS")
		)
		(fp_line
			(start -0.12065 -0.305054)
			(end -0.12065 -0.2794)
			(stroke
				(width 0.1)
				(type default)
			)
			(layer "F.Fab")
		)
		(fp_line
			(start -0.67945 -0.305054)
			(end -0.12065 -0.305054)
			(stroke
				(width 0.1)
				(type default)
			)
			(layer "F.Fab")
		)
		(fp_line
			(start 0.67945 -0.3048)
			(end 0.67945 0.3048)
			(stroke
				(width 0.1)
				(type default)
			)
			(layer "F.Fab")
		)
		(fp_line
			(start 0.12065 -0.3048)
			(end 0.67945 -0.3048)
			(stroke
				(width 0.1)
				(type default)
			)
			(layer "F.Fab")
		)
		(fp_line
			(start 0.12065 -0.2794)
			(end 0.12065 -0.3048)
			(stroke
				(width 0.1)
				(type default)
			)
			(layer "F.Fab")
		)
		(fp_line
			(start -0.12065 -0.2794)
			(end 0.12065 -0.2794)
			(stroke
				(width 0.1)
				(type default)
			)
			(layer "F.Fab")
		)
		(fp_line
			(start 0.120396 0.2794)
			(end -0.12065 0.2794)
			(stroke
				(width 0.1)
				(type default)
			)
			(layer "F.Fab")
		)
		(fp_line
			(start -0.12065 0.2794)
			(end -0.12065 0.3048)
			(stroke
				(width 0.1)
				(type default)
			)
			(layer "F.Fab")
		)
		(fp_line
			(start 0.67945 0.3048)
			(end 0.120396 0.3048)
			(stroke
				(width 0.1)
				(type default)
			)
			(layer "F.Fab")
		)
		(fp_line
			(start 0.120396 0.3048)
			(end 0.120396 0.2794)
			(stroke
				(width 0.1)
				(type default)
			)
			(layer "F.Fab")
		)
		(fp_line
			(start -0.12065 0.3048)
			(end -0.67945 0.3048)
			(stroke
				(width 0.1)
				(type default)
			)
			(layer "F.Fab")
		)
		(fp_line
			(start -0.67945 0.3048)
			(end -0.67945 -0.305054)
			(stroke
				(width 0.1)
				(type default)
			)
			(layer "F.Fab")
		)
		(pad "1" smd rect
			(at -0.40005 0 270)
			(size 0.4572 0.508)
			(layers "F.Cu" "F.Mask" "F.Paste")
			(net "P3V3_AUX")
		)
		(pad "2" smd rect
			(at 0.40005 0 270)
			(size 0.4572 0.508)
			(layers "F.Cu" "F.Mask" "F.Paste")
			(net "FAB_BMC_REV_ID2")
		)
	)
	(footprint ""
		(layer "F.Cu")
		(at 95.706438 -338.86013)
		(property "Reference" "PR326"
			(at 0 0 0)
			(layer "F.SilkS")
			(hide yes)
			(effects
				(font
					(size 1.27 1.27)
				)
			)
		)
		(property "Value" ""
			(at 0 0 0)
			(layer "F.Fab")
			(effects
				(font
					(size 1.27 1.27)
				)
			)
		)
		(duplicate_pad_numbers_are_jumpers no)
		(fp_line
			(start -0.7874 -0.4064)
			(end 0.7874 -0.4064)
			(stroke
				(width 0.1524)
				(type default)
			)
			(layer "F.SilkS")
		)
		(fp_line
			(start -0.7874 0.4064)
			(end -0.7874 -0.4064)
			(stroke
				(width 0.1524)
				(type default)
			)
			(layer "F.SilkS")
		)
		(fp_line
			(start 0.7874 -0.4064)
			(end 0.7874 0.4064)
			(stroke
				(width 0.1524)
				(type default)
			)
			(layer "F.SilkS")
		)
		(fp_line
			(start 0.7874 0.4064)
			(end -0.7874 0.4064)
			(stroke
				(width 0.1524)
				(type default)
			)
			(layer "F.SilkS")
		)
		(fp_line
			(start -0.67945 -0.305054)
			(end -0.12065 -0.305054)
			(stroke
				(width 0.1)
				(type default)
			)
			(layer "F.Fab")
		)
		(fp_line
			(start -0.67945 0.3048)
			(end -0.67945 -0.305054)
			(stroke
				(width 0.1)
				(type default)
			)
			(layer "F.Fab")
		)
		(fp_line
			(start -0.12065 -0.305054)
			(end -0.12065 -0.2794)
			(stroke
				(width 0.1)
				(type default)
			)
			(layer "F.Fab")
		)
		(fp_line
			(start -0.12065 -0.2794)
			(end 0.12065 -0.2794)
			(stroke
				(width 0.1)
				(type default)
			)
			(layer "F.Fab")
		)
		(fp_line
			(start -0.12065 0.2794)
			(end -0.12065 0.3048)
			(stroke
				(width 0.1)
				(type default)
			)
			(layer "F.Fab")
		)
		(fp_line
			(start -0.12065 0.3048)
			(end -0.67945 0.3048)
			(stroke
				(width 0.1)
				(type default)
			)
			(layer "F.Fab")
		)
		(fp_line
			(start 0.120396 0.2794)
			(end -0.12065 0.2794)
			(stroke
				(width 0.1)
				(type default)
			)
			(layer "F.Fab")
		)
		(fp_line
			(start 0.120396 0.3048)
			(end 0.120396 0.2794)
			(stroke
				(width 0.1)
				(type default)
			)
			(layer "F.Fab")
		)
		(fp_line
			(start 0.12065 -0.3048)
			(end 0.67945 -0.3048)
			(stroke
				(width 0.1)
				(type default)
			)
			(layer "F.Fab")
		)
		(fp_line
			(start 0.12065 -0.2794)
			(end 0.12065 -0.3048)
			(stroke
				(width 0.1)
				(type default)
			)
			(layer "F.Fab")
		)
		(fp_line
			(start 0.67945 -0.3048)
			(end 0.67945 0.3048)
			(stroke
				(width 0.1)
				(type default)
			)
			(layer "F.Fab")
		)
		(fp_line
			(start 0.67945 0.3048)
			(end 0.120396 0.3048)
			(stroke
				(width 0.1)
				(type default)
			)
			(layer "F.Fab")
		)
		(pad "1" smd circle
			(at -0.40005 0)
			(size 0 0)
			(layers "F.Cu" "F.Mask" "F.Paste")
			(net "PVCCIN_CPU1_LSET1")
		)
		(pad "2" smd circle
			(at 0.40005 0)
			(size 0 0)
			(layers "F.Cu" "F.Mask" "F.Paste")
			(net "GND")
		)
	)
	(footprint ""
		(layer "F.Cu")
		(at 155.742386 -64.761364)
		(property "Reference" "U134"
			(at -1.4732 2.041652 0)
			(unlocked yes)
			(layer "F.SilkS")
			(effects
				(font
					(size 0.7874 0.5842)
					(thickness 0.1524)
				)
				(justify left)
			)
		)
		(property "Value" ""
			(at 0 0 0)
			(layer "F.Fab")
			(effects
				(font
					(size 1.27 1.27)
				)
			)
		)
		(duplicate_pad_numbers_are_jumpers no)
		(fp_line
			(start -1.38176 -1.100074)
			(end -1.38176 1.100074)
			(stroke
				(width 0.1524)
				(type default)
			)
			(layer "F.SilkS")
		)
		(fp_line
			(start -1.38176 1.100074)
			(end 1.38176 1.100074)
			(stroke
				(width 0.1524)
				(type default)
			)
			(layer "F.SilkS")
		)
		(fp_line
			(start -0.592074 -1.100074)
			(end -1.38176 -1.100074)
			(stroke
				(width 0.1524)
				(type default)
			)
			(layer "F.SilkS")
		)
		(fp_line
			(start 0 -0.508)
			(end -0.592074 -1.100074)
			(stroke
				(width 0.1524)
				(type default)
			)
			(layer "F.SilkS")
		)
		(fp_line
			(start 0.592074 -1.100074)
			(end 0 -0.508)
			(stroke
				(width 0.1524)
				(type default)
			)
			(layer "F.SilkS")
		)
		(fp_line
			(start 1.38176 -1.100074)
			(end 0.592074 -1.100074)
			(stroke
				(width 0.1524)
				(type default)
			)
			(layer "F.SilkS")
		)
		(fp_line
			(start 1.38176 1.100074)
			(end 1.38176 -1.100074)
			(stroke
				(width 0.1524)
				(type default)
			)
			(layer "F.SilkS")
		)
		(fp_poly
			(pts
				(xy -0.989584 -1.349248) (xy -1.209802 -1.789938) (xy -0.769366 -1.789938)
			)
			(stroke
				(width 0)
				(type default)
			)
			(fill yes)
			(layer "F.SilkS")
		)
		(fp_line
			(start -0.674878 -1.100074)
			(end -0.674878 1.100074)
			(stroke
				(width 0.1)
				(type default)
			)
			(layer "F.Fab")
		)
		(fp_line
			(start -0.674878 1.100074)
			(end 0.674878 1.100074)
			(stroke
				(width 0.1)
				(type default)
			)
			(layer "F.Fab")
		)
		(fp_line
			(start 0.674878 -1.100074)
			(end -0.674878 -1.100074)
			(stroke
				(width 0.1)
				(type default)
			)
			(layer "F.Fab")
		)
		(fp_line
			(start 0.674878 1.100074)
			(end 0.674878 -1.100074)
			(stroke
				(width 0.1)
				(type default)
			)
			(layer "F.Fab")
		)
		(fp_poly
			(pts
				(xy -1.9431 -0.870204) (xy -1.50241 -0.649986) (xy -1.9431 -0.429768)
			)
			(stroke
				(width 0)
				(type default)
			)
			(fill yes)
			(layer "F.Fab")
		)
		(pad "1" smd rect
			(at -0.94996 -0.649986 270)
			(size 0.4318 0.6096)
			(layers "F.Cu" "F.Mask" "F.Paste")
			(net "RST_SMB_E1S_N")
		)
		(pad "2" smd rect
			(at -0.94996 0 270)
			(size 0.4318 0.6096)
			(layers "F.Cu" "F.Mask" "F.Paste")
			(net "GND")
		)
		(pad "3" smd rect
			(at -0.94996 0.649986 270)
			(size 0.4318 0.6096)
			(layers "F.Cu" "F.Mask" "F.Paste")
			(net "RST_SMB_E1S_N")
		)
		(pad "4" smd rect
			(at 0.94996 0.649986 270)
			(size 0.4318 0.6096)
			(layers "F.Cu" "F.Mask" "F.Paste")
			(net "SMB_PCIE_E1S_ISO_EN_R2")
		)
		(pad "5" smd rect
			(at 0.94996 0 270)
			(size 0.4318 0.6096)
			(layers "F.Cu" "F.Mask" "F.Paste")
			(net "P3V3_AUX")
		)
		(pad "6" smd rect
			(at 0.94996 -0.649986 270)
			(size 0.4318 0.6096)
			(layers "F.Cu" "F.Mask" "F.Paste")
			(net "RST_SMB_BUF_E1S_0_N")
		)
	)
)
